(kicad_pcb
	(version 20260206)
	(generator "pcbnew")
	(generator_version "10.0")
	(general
		(thickness 1.6)
		(legacy_teardrops no)
	)
	(paper "A4")
	(title_block
		(title "Bryce Canyon_IOM_IOC_16318-2_OCP.brd")
		(comment 1 "Bryce Canyon / footprints 1305-1311 of 1605")
	)
	(layers
		(0 "F.Cu" signal "TOP")
		(4 "In1.Cu" signal "L2GND")
		(6 "In2.Cu" signal "L3")
		(8 "In3.Cu" signal "L4VCC")
		(10 "In4.Cu" signal "L5VCC")
		(12 "In5.Cu" signal "L6")
		(14 "In6.Cu" signal "L7GND")
		(2 "B.Cu" signal "BOTTOM")
		(9 "F.Adhes" user "F.Adhesive")
		(11 "B.Adhes" user "B.Adhesive")
		(13 "F.Paste" user "Package Geometry/Pastemask Top")
		(15 "B.Paste" user "Package Geometry/Pastemask Bottom")
		(5 "F.SilkS" user "Ref Des/Silkscreen Top")
		(7 "B.SilkS" user "Ref Des/Silkscreen Bottom")
		(1 "F.Mask" user "Board Geometry/Soldermask Top")
		(3 "B.Mask" user "Board Geometry/Soldermask Bottom")
		(17 "Dwgs.User" user "User.Drawings")
		(19 "Cmts.User" user "User.Comments")
		(21 "Eco1.User" user "User.Eco1")
		(23 "Eco2.User" user "User.Eco2")
		(25 "Edge.Cuts" user "Board Geometry/Outline")
		(27 "Margin" user)
		(31 "F.CrtYd" user "Package Geometry/Place Bound Top")
		(29 "B.CrtYd" user "Package Geometry/Place Bound Bottom")
		(35 "F.Fab" user "Ref Des/Assembly Top")
		(33 "B.Fab" user "Ref Des/Assembly Bottom")
	)
	(footprint ""
		(layer "B.Cu")
		(at 193.9798 -65.3796 90)
		(property "Reference" "C401"
			(at 0 0 90)
			(layer "B.SilkS")
			(hide yes)
			(effects
				(font
					(size 1.27 1.27)
				)
				(justify mirror)
			)
		)
		(property "Value" "SCD1U6D3V1KX-GP"
			(at 2.8321 -1.7399 90)
			(unlocked yes)
			(layer "B.Fab")
			(hide yes)
			(effects
				(font
					(size 1.016 1.016)
					(thickness 0.1524)
				)
				(justify mirror)
			)
		)
		(property "Device Type" "C0201H13"
			(at 2.8321 -3.2639 90)
			(unlocked yes)
			(layer "B.Fab")
			(hide yes)
			(effects
				(font
					(size 1.016 1.016)
					(thickness 0.1524)
				)
				(justify mirror)
			)
		)
		(duplicate_pad_numbers_are_jumpers no)
		(fp_rect
			(start 0.2794 0.6477)
			(end -0.2794 -0.6477)
			(stroke
				(width 0)
				(type default)
			)
			(fill no)
			(layer "B.CrtYd")
		)
		(fp_rect
			(start 0.2794 0.6477)
			(end -0.2794 -0.6477)
			(stroke
				(width 0)
				(type default)
			)
			(fill no)
			(layer "B.Fab")
		)
		(pad "1" smd custom
			(at 0 -0.2794 270)
			(size 0.0762 0.0762)
			(layers "B.Cu" "B.Mask" "B.Paste")
			(net "P0V975")
			(options
				(clearance outline)
				(anchor circle)
			)
			(primitives
				(gr_poly
					(pts
						(arc
							(start 0.1524 0.127)
							(mid 0.137521 0.162921)
							(end 0.1016 0.1778)
						)
						(arc
							(start -0.1016 0.1778)
							(mid -0.137521 0.162921)
							(end -0.1524 0.127)
						)
						(arc
							(start -0.1524 -0.127)
							(mid -0.137521 -0.162921)
							(end -0.1016 -0.1778)
						)
						(arc
							(start 0.1016 -0.1778)
							(mid 0.137521 -0.162921)
							(end 0.1524 -0.127)
						)
					)
					(width 0)
					(fill yes)
				)
			)
		)
		(pad "2" smd custom
			(at 0 0.2794 270)
			(size 0.0762 0.0762)
			(layers "B.Cu" "B.Mask" "B.Paste")
			(net "GND")
			(options
				(clearance outline)
				(anchor circle)
			)
			(primitives
				(gr_poly
					(pts
						(arc
							(start 0.1524 0.127)
							(mid 0.137521 0.162921)
							(end 0.1016 0.1778)
						)
						(arc
							(start -0.1016 0.1778)
							(mid -0.137521 0.162921)
							(end -0.1524 0.127)
						)
						(arc
							(start -0.1524 -0.127)
							(mid -0.137521 -0.162921)
							(end -0.1016 -0.1778)
						)
						(arc
							(start 0.1016 -0.1778)
							(mid 0.137521 -0.162921)
							(end 0.1524 -0.127)
						)
					)
					(width 0)
					(fill yes)
				)
			)
		)
	)
	(footprint ""
		(layer "B.Cu")
		(at 54.777132 -123.249182)
		(property "Reference" "R345"
			(at 0 0 0)
			(layer "B.SilkS")
			(hide yes)
			(effects
				(font
					(size 1.27 1.27)
				)
				(justify mirror)
			)
		)
		(property "Value" "0R2J-2-GP"
			(at -0.064008 -3.993896 0)
			(unlocked yes)
			(layer "B.Fab")
			(hide yes)
			(effects
				(font
					(size 1.016 1.016)
					(thickness 0.1524)
				)
				(justify mirror)
			)
		)
		(property "Device Type" "R402H16"
			(at -0.064008 -5.517896 0)
			(unlocked yes)
			(layer "B.Fab")
			(hide yes)
			(effects
				(font
					(size 1.016 1.016)
					(thickness 0.1524)
				)
				(justify mirror)
			)
		)
		(duplicate_pad_numbers_are_jumpers no)
		(fp_line
			(start -0.508 -0.9398)
			(end 0.508 -0.9398)
			(stroke
				(width 0.1524)
				(type default)
			)
			(layer "B.SilkS")
		)
		(fp_line
			(start 0.508 -0.9398)
			(end 0.508 0.9398)
			(stroke
				(width 0.1524)
				(type default)
			)
			(layer "B.SilkS")
		)
		(fp_rect
			(start 0.508 0.9398)
			(end -0.508 -0.9398)
			(stroke
				(width 0)
				(type default)
			)
			(fill no)
			(layer "B.CrtYd")
		)
		(fp_rect
			(start 0.508 0.9398)
			(end -0.508 -0.9398)
			(stroke
				(width 0)
				(type default)
			)
			(fill no)
			(layer "B.Fab")
		)
		(pad "1" smd custom
			(at 0 -0.4445 180)
			(size 0.1397 0.1397)
			(layers "B.Cu" "B.Mask" "B.Paste")
			(net "DEBUG_RST_BTN_N_R")
			(options
				(clearance outline)
				(anchor circle)
			)
			(primitives
				(gr_poly
					(pts
						(arc
							(start -0.1778 0.2794)
							(mid -0.249642 0.249642)
							(end -0.2794 0.1778)
						)
						(arc
							(start -0.2794 -0.1778)
							(mid -0.249642 -0.249642)
							(end -0.1778 -0.2794)
						)
						(arc
							(start 0.1778 -0.2794)
							(mid 0.249642 -0.249642)
							(end 0.2794 -0.1778)
						)
						(arc
							(start 0.2794 0.1778)
							(mid 0.249642 0.249642)
							(end 0.1778 0.2794)
						)
					)
					(width 0)
					(fill yes)
				)
			)
		)
		(pad "2" smd custom
			(at 0 0.4445 180)
			(size 0.1397 0.1397)
			(layers "B.Cu" "B.Mask" "B.Paste")
			(net "DEBUG_RST_BTN_N")
			(options
				(clearance outline)
				(anchor circle)
			)
			(primitives
				(gr_poly
					(pts
						(arc
							(start -0.1778 0.2794)
							(mid -0.249642 0.249642)
							(end -0.2794 0.1778)
						)
						(arc
							(start -0.2794 -0.1778)
							(mid -0.249642 -0.249642)
							(end -0.1778 -0.2794)
						)
						(arc
							(start 0.1778 -0.2794)
							(mid 0.249642 -0.249642)
							(end 0.2794 -0.1778)
						)
						(arc
							(start 0.2794 0.1778)
							(mid 0.249642 0.249642)
							(end 0.1778 0.2794)
						)
					)
					(width 0)
					(fill yes)
				)
			)
		)
	)
	(footprint ""
		(layer "B.Cu")
		(at 204.815948 -51.430682 -90)
		(property "Reference" "C338"
			(at 0 0 90)
			(layer "B.SilkS")
			(hide yes)
			(effects
				(font
					(size 1.27 1.27)
				)
				(justify mirror)
			)
		)
		(property "Value" "SC22U6D3V3MX-9-GP-U"
			(at 0 -2.8194 270)
			(unlocked yes)
			(layer "B.Fab")
			(hide yes)
			(effects
				(font
					(size 1.016 1.016)
					(thickness 0.1524)
				)
				(justify mirror)
			)
		)
		(property "Device Type" "C603H40"
			(at 0 -4.3434 270)
			(unlocked yes)
			(layer "B.Fab")
			(hide yes)
			(effects
				(font
					(size 1.016 1.016)
					(thickness 0.1524)
				)
				(justify mirror)
			)
		)
		(duplicate_pad_numbers_are_jumpers no)
		(fp_line
			(start -0.508 0)
			(end 0.508 0)
			(stroke
				(width 0.2032)
				(type default)
			)
			(layer "B.SilkS")
		)
		(fp_rect
			(start 0.5842 1.3335)
			(end -0.5842 -1.3335)
			(stroke
				(width 0)
				(type default)
			)
			(fill no)
			(layer "B.CrtYd")
		)
		(fp_rect
			(start 0.5842 1.3335)
			(end -0.5842 -1.3335)
			(stroke
				(width 0)
				(type default)
			)
			(fill no)
			(layer "B.Fab")
		)
		(pad "1" smd custom
			(at 0 -0.762 90)
			(size 0.2159 0.2159)
			(layers "B.Cu" "B.Mask" "B.Paste")
			(net "SHELL_PLL_VDD")
			(options
				(clearance outline)
				(anchor circle)
			)
			(primitives
				(gr_poly
					(pts
						(arc
							(start -0.3302 0.4318)
							(mid -0.402042 0.402042)
							(end -0.4318 0.3302)
						)
						(arc
							(start -0.4318 -0.3302)
							(mid -0.402042 -0.402042)
							(end -0.3302 -0.4318)
						)
						(arc
							(start 0.3302 -0.4318)
							(mid 0.402042 -0.402042)
							(end 0.4318 -0.3302)
						)
						(arc
							(start 0.4318 0.3302)
							(mid 0.402042 0.402042)
							(end 0.3302 0.4318)
						)
					)
					(width 0)
					(fill yes)
				)
			)
		)
		(pad "2" smd custom
			(at 0 0.762 90)
			(size 0.2159 0.2159)
			(layers "B.Cu" "B.Mask" "B.Paste")
			(net "GND")
			(options
				(clearance outline)
				(anchor circle)
			)
			(primitives
				(gr_poly
					(pts
						(arc
							(start -0.3302 0.4318)
							(mid -0.402042 0.402042)
							(end -0.4318 0.3302)
						)
						(arc
							(start -0.4318 -0.3302)
							(mid -0.402042 -0.402042)
							(end -0.3302 -0.4318)
						)
						(arc
							(start 0.3302 -0.4318)
							(mid 0.402042 -0.402042)
							(end 0.4318 -0.3302)
						)
						(arc
							(start 0.4318 0.3302)
							(mid 0.402042 0.402042)
							(end 0.3302 0.4318)
						)
					)
					(width 0)
					(fill yes)
				)
			)
		)
	)
	(footprint ""
		(layer "B.Cu")
		(at 93.853 -145.8976 180)
		(property "Reference" "R430"
			(at 0 0 0)
			(layer "B.SilkS")
			(hide yes)
			(effects
				(font
					(size 1.27 1.27)
				)
				(justify mirror)
			)
		)
		(property "Value" "4K7R2F-GP"
			(at -0.064008 -3.993896 180)
			(unlocked yes)
			(layer "B.Fab")
			(hide yes)
			(effects
				(font
					(size 1.016 1.016)
					(thickness 0.1524)
				)
				(justify mirror)
			)
		)
		(property "Device Type" "R402H16"
			(at -0.064008 -5.517896 180)
			(unlocked yes)
			(layer "B.Fab")
			(hide yes)
			(effects
				(font
					(size 1.016 1.016)
					(thickness 0.1524)
				)
				(justify mirror)
			)
		)
		(duplicate_pad_numbers_are_jumpers no)
		(fp_line
			(start 0.508 -0.9398)
			(end 0.508 0.9398)
			(stroke
				(width 0.1524)
				(type default)
			)
			(layer "B.SilkS")
		)
		(fp_line
			(start -0.508 -0.9398)
			(end 0.508 -0.9398)
			(stroke
				(width 0.1524)
				(type default)
			)
			(layer "B.SilkS")
		)
		(fp_rect
			(start 0.508 0.9398)
			(end -0.508 -0.9398)
			(stroke
				(width 0)
				(type default)
			)
			(fill no)
			(layer "B.CrtYd")
		)
		(fp_rect
			(start 0.508 0.9398)
			(end -0.508 -0.9398)
			(stroke
				(width 0)
				(type default)
			)
			(fill no)
			(layer "B.Fab")
		)
		(pad "1" smd custom
			(at 0 -0.4445)
			(size 0.1397 0.1397)
			(layers "B.Cu" "B.Mask" "B.Paste")
			(net "TCA9555_A2")
			(options
				(clearance outline)
				(anchor circle)
			)
			(primitives
				(gr_poly
					(pts
						(arc
							(start -0.1778 0.2794)
							(mid -0.249642 0.249642)
							(end -0.2794 0.1778)
						)
						(arc
							(start -0.2794 -0.1778)
							(mid -0.249642 -0.249642)
							(end -0.1778 -0.2794)
						)
						(arc
							(start 0.1778 -0.2794)
							(mid 0.249642 -0.249642)
							(end 0.2794 -0.1778)
						)
						(arc
							(start 0.2794 0.1778)
							(mid 0.249642 0.249642)
							(end 0.1778 0.2794)
						)
					)
					(width 0)
					(fill yes)
				)
			)
		)
		(pad "2" smd custom
			(at 0 0.4445)
			(size 0.1397 0.1397)
			(layers "B.Cu" "B.Mask" "B.Paste")
			(net "GND")
			(options
				(clearance outline)
				(anchor circle)
			)
			(primitives
				(gr_poly
					(pts
						(arc
							(start -0.1778 0.2794)
							(mid -0.249642 0.249642)
							(end -0.2794 0.1778)
						)
						(arc
							(start -0.2794 -0.1778)
							(mid -0.249642 -0.249642)
							(end -0.1778 -0.2794)
						)
						(arc
							(start 0.1778 -0.2794)
							(mid 0.249642 -0.249642)
							(end 0.2794 -0.1778)
						)
						(arc
							(start 0.2794 0.1778)
							(mid 0.249642 0.249642)
							(end 0.1778 0.2794)
						)
					)
					(width 0)
					(fill yes)
				)
			)
		)
	)
	(footprint ""
		(layer "B.Cu")
		(at 92.8116 -129.4892 180)
		(property "Reference" "C126"
			(at 0 0 0)
			(layer "B.SilkS")
			(hide yes)
			(effects
				(font
					(size 1.27 1.27)
				)
				(justify mirror)
			)
		)
		(property "Value" "SCD1U16V2KX-3GP"
			(at -1.1811 -2.7051 180)
			(unlocked yes)
			(layer "B.Fab")
			(hide yes)
			(effects
				(font
					(size 1.016 1.016)
					(thickness 0.1524)
				)
				(justify mirror)
			)
		)
		(property "Device Type" "C402H22"
			(at -1.1811 -4.2291 180)
			(unlocked yes)
			(layer "B.Fab")
			(hide yes)
			(effects
				(font
					(size 1.016 1.016)
					(thickness 0.1524)
				)
				(justify mirror)
			)
		)
		(duplicate_pad_numbers_are_jumpers no)
		(fp_rect
			(start 0.4318 0.9525)
			(end -0.4318 -0.9525)
			(stroke
				(width 0)
				(type default)
			)
			(fill no)
			(layer "B.CrtYd")
		)
		(fp_rect
			(start 0.4318 0.9525)
			(end -0.4318 -0.9525)
			(stroke
				(width 0)
				(type default)
			)
			(fill no)
			(layer "B.Fab")
		)
		(pad "1" smd custom
			(at 0 -0.4445)
			(size 0.1524 0.1524)
			(layers "B.Cu" "B.Mask" "B.Paste")
			(net "P3V3_STBY")
			(options
				(clearance outline)
				(anchor circle)
			)
			(primitives
				(gr_poly
					(pts
						(arc
							(start 0.3048 0.2032)
							(mid 0.275042 0.275042)
							(end 0.2032 0.3048)
						)
						(arc
							(start -0.2032 0.3048)
							(mid -0.275042 0.275042)
							(end -0.3048 0.2032)
						)
						(arc
							(start -0.3048 -0.2032)
							(mid -0.275042 -0.275042)
							(end -0.2032 -0.3048)
						)
						(arc
							(start 0.2032 -0.3048)
							(mid 0.275042 -0.275042)
							(end 0.3048 -0.2032)
						)
					)
					(width 0)
					(fill yes)
				)
			)
		)
		(pad "2" smd custom
			(at 0 0.4445)
			(size 0.1524 0.1524)
			(layers "B.Cu" "B.Mask" "B.Paste")
			(net "GND")
			(options
				(clearance outline)
				(anchor circle)
			)
			(primitives
				(gr_poly
					(pts
						(arc
							(start 0.3048 0.2032)
							(mid 0.275042 0.275042)
							(end 0.2032 0.3048)
						)
						(arc
							(start -0.2032 0.3048)
							(mid -0.275042 0.275042)
							(end -0.3048 0.2032)
						)
						(arc
							(start -0.3048 -0.2032)
							(mid -0.275042 -0.275042)
							(end -0.2032 -0.3048)
						)
						(arc
							(start 0.2032 -0.3048)
							(mid 0.275042 -0.275042)
							(end 0.3048 -0.2032)
						)
					)
					(width 0)
					(fill yes)
				)
			)
		)
	)
	(footprint ""
		(layer "B.Cu")
		(at 50.4825 -154.3304 90)
		(property "Reference" "R279"
			(at 0 0 90)
			(layer "B.SilkS")
			(hide yes)
			(effects
				(font
					(size 1.27 1.27)
				)
				(justify mirror)
			)
		)
		(property "Value" "0R2J-2-GP"
			(at -0.064008 -3.993896 90)
			(unlocked yes)
			(layer "B.Fab")
			(hide yes)
			(effects
				(font
					(size 1.016 1.016)
					(thickness 0.1524)
				)
				(justify mirror)
			)
		)
		(property "Device Type" "R402H16"
			(at -0.064008 -5.517896 90)
			(unlocked yes)
			(layer "B.Fab")
			(hide yes)
			(effects
				(font
					(size 1.016 1.016)
					(thickness 0.1524)
				)
				(justify mirror)
			)
		)
		(duplicate_pad_numbers_are_jumpers no)
		(fp_line
			(start 0.508 -0.9398)
			(end 0.508 0.9398)
			(stroke
				(width 0.1524)
				(type default)
			)
			(layer "B.SilkS")
		)
		(fp_line
			(start -0.508 -0.9398)
			(end 0.508 -0.9398)
			(stroke
				(width 0.1524)
				(type default)
			)
			(layer "B.SilkS")
		)
		(fp_rect
			(start 0.508 0.9398)
			(end -0.508 -0.9398)
			(stroke
				(width 0)
				(type default)
			)
			(fill no)
			(layer "B.CrtYd")
		)
		(fp_rect
			(start 0.508 0.9398)
			(end -0.508 -0.9398)
			(stroke
				(width 0)
				(type default)
			)
			(fill no)
			(layer "B.Fab")
		)
		(pad "1" smd custom
			(at 0 -0.4445 270)
			(size 0.1397 0.1397)
			(layers "B.Cu" "B.Mask" "B.Paste")
			(net "I2C_MEZZ_OOB_SCL")
			(options
				(clearance outline)
				(anchor circle)
			)
			(primitives
				(gr_poly
					(pts
						(arc
							(start -0.1778 0.2794)
							(mid -0.249642 0.249642)
							(end -0.2794 0.1778)
						)
						(arc
							(start -0.2794 -0.1778)
							(mid -0.249642 -0.249642)
							(end -0.1778 -0.2794)
						)
						(arc
							(start 0.1778 -0.2794)
							(mid 0.249642 -0.249642)
							(end 0.2794 -0.1778)
						)
						(arc
							(start 0.2794 0.1778)
							(mid 0.249642 0.249642)
							(end 0.1778 0.2794)
						)
					)
					(width 0)
					(fill yes)
				)
			)
		)
		(pad "2" smd custom
			(at 0 0.4445 270)
			(size 0.1397 0.1397)
			(layers "B.Cu" "B.Mask" "B.Paste")
			(net "BMC_SMB5_CLK")
			(options
				(clearance outline)
				(anchor circle)
			)
			(primitives
				(gr_poly
					(pts
						(arc
							(start -0.1778 0.2794)
							(mid -0.249642 0.249642)
							(end -0.2794 0.1778)
						)
						(arc
							(start -0.2794 -0.1778)
							(mid -0.249642 -0.249642)
							(end -0.1778 -0.2794)
						)
						(arc
							(start 0.1778 -0.2794)
							(mid 0.249642 -0.249642)
							(end 0.2794 -0.1778)
						)
						(arc
							(start 0.2794 0.1778)
							(mid 0.249642 0.249642)
							(end 0.1778 0.2794)
						)
					)
					(width 0)
					(fill yes)
				)
			)
		)
	)
	(footprint ""
		(layer "B.Cu")
		(at 46.10227 -146.962114)
		(property "Reference" "C108"
			(at 0 0 0)
			(layer "B.SilkS")
			(hide yes)
			(effects
				(font
					(size 1.27 1.27)
				)
				(justify mirror)
			)
		)
		(property "Value" "SC1U16V3KX-5GP"
			(at 0 -2.8194 0)
			(unlocked yes)
			(layer "B.Fab")
			(hide yes)
			(effects
				(font
					(size 1.016 1.016)
					(thickness 0.1524)
				)
				(justify mirror)
			)
		)
		(property "Device Type" "C603H36"
			(at 0 -4.3434 0)
			(unlocked yes)
			(layer "B.Fab")
			(hide yes)
			(effects
				(font
					(size 1.016 1.016)
					(thickness 0.1524)
				)
				(justify mirror)
			)
		)
		(duplicate_pad_numbers_are_jumpers no)
		(fp_line
			(start -0.508 0)
			(end 0.508 0)
			(stroke
				(width 0.2032)
				(type default)
			)
			(layer "B.SilkS")
		)
		(fp_rect
			(start 0.5842 1.3335)
			(end -0.5842 -1.3335)
			(stroke
				(width 0)
				(type default)
			)
			(fill no)
			(layer "B.CrtYd")
		)
		(fp_rect
			(start 0.5842 1.3335)
			(end -0.5842 -1.3335)
			(stroke
				(width 0)
				(type default)
			)
			(fill no)
			(layer "B.Fab")
		)
		(pad "1" smd custom
			(at 0 -0.762 180)
			(size 0.2159 0.2159)
			(layers "B.Cu" "B.Mask" "B.Paste")
			(net "P1V15_STBY")
			(options
				(clearance outline)
				(anchor circle)
			)
			(primitives
				(gr_poly
					(pts
						(arc
							(start -0.3302 0.4318)
							(mid -0.402042 0.402042)
							(end -0.4318 0.3302)
						)
						(arc
							(start -0.4318 -0.3302)
							(mid -0.402042 -0.402042)
							(end -0.3302 -0.4318)
						)
						(arc
							(start 0.3302 -0.4318)
							(mid 0.402042 -0.402042)
							(end 0.4318 -0.3302)
						)
						(arc
							(start 0.4318 0.3302)
							(mid 0.402042 0.402042)
							(end 0.3302 0.4318)
						)
					)
					(width 0)
					(fill yes)
				)
			)
		)
		(pad "2" smd custom
			(at 0 0.762 180)
			(size 0.2159 0.2159)
			(layers "B.Cu" "B.Mask" "B.Paste")
			(net "GND")
			(options
				(clearance outline)
				(anchor circle)
			)
			(primitives
				(gr_poly
					(pts
						(arc
							(start -0.3302 0.4318)
							(mid -0.402042 0.402042)
							(end -0.4318 0.3302)
						)
						(arc
							(start -0.4318 -0.3302)
							(mid -0.402042 -0.402042)
							(end -0.3302 -0.4318)
						)
						(arc
							(start 0.3302 -0.4318)
							(mid 0.402042 -0.402042)
							(end 0.4318 -0.3302)
						)
						(arc
							(start 0.4318 0.3302)
							(mid 0.402042 0.402042)
							(end 0.3302 0.4318)
						)
					)
					(width 0)
					(fill yes)
				)
			)
		)
	)
)
